(kicad_pcb
	(version 20260206)
	(generator "pcbnew")
	(generator_version "10.0")
	(general
		(thickness 1.6)
		(legacy_teardrops no)
	)
	(paper "A4")
	(title_block
		(title "04192023_DAF0TMB3IC0_F0TG_MB_C_brd_V02_OCP.brd")
		(comment 1 "Grand Teton / footprints 4989-4994 of 8354")
	)
	(layers
		(0 "F.Cu" signal "TOP")
		(4 "In1.Cu" signal "GND")
		(6 "In2.Cu" signal "IN1")
		(8 "In3.Cu" signal "GND1")
		(10 "In4.Cu" signal "IN2")
		(12 "In5.Cu" signal "GND2")
		(14 "In6.Cu" signal "IN3")
		(16 "In7.Cu" signal "GND3")
		(18 "In8.Cu" signal "VCC")
		(20 "In9.Cu" signal "VCC1")
		(22 "In10.Cu" signal "GND4")
		(24 "In11.Cu" signal "IN4")
		(26 "In12.Cu" signal "GND5")
		(28 "In13.Cu" signal "IN5")
		(30 "In14.Cu" signal "GND6")
		(32 "In15.Cu" signal "IN6")
		(34 "In16.Cu" signal "GND7")
		(2 "B.Cu" signal "BOTTOM")
		(9 "F.Adhes" user "F.Adhesive")
		(11 "B.Adhes" user "B.Adhesive")
		(13 "F.Paste" user "Package Geometry/Pastemask Top")
		(15 "B.Paste" user "Package Geometry/Pastemask Bottom")
		(5 "F.SilkS" user "Ref Des/Silkscreen Top")
		(7 "B.SilkS" user "Ref Des/Silkscreen Bottom")
		(1 "F.Mask" user "Board Geometry/Soldermask Top")
		(3 "B.Mask" user "Board Geometry/Soldermask Bottom")
		(17 "Dwgs.User" user "User.Drawings")
		(19 "Cmts.User" user "User.Comments")
		(21 "Eco1.User" user "User.Eco1")
		(23 "Eco2.User" user "User.Eco2")
		(25 "Edge.Cuts" user "Board Geometry/Outline")
		(27 "Margin" user)
		(31 "F.CrtYd" user "Package Geometry/Place Bound Top")
		(29 "B.CrtYd" user "Package Geometry/Place Bound Bottom")
		(35 "F.Fab" user "Ref Des/Assembly Top")
		(33 "B.Fab" user "Ref Des/Assembly Bottom")
	)
	(footprint ""
		(layer "B.Cu")
		(at 418.618924 -398.942052 90)
		(property "Reference" "C969"
			(at 0 0 90)
			(layer "B.SilkS")
			(hide yes)
			(effects
				(font
					(size 1.27 1.27)
				)
				(justify mirror)
			)
		)
		(property "Value" ""
			(at 0 0 90)
			(layer "B.Fab")
			(effects
				(font
					(size 1.27 1.27)
				)
				(justify mirror)
			)
		)
		(duplicate_pad_numbers_are_jumpers no)
		(fp_line
			(start 0.7874 -0.4064)
			(end -0.7874 -0.4064)
			(stroke
				(width 0.1524)
				(type default)
			)
			(layer "B.SilkS")
		)
		(fp_line
			(start -0.7874 -0.4064)
			(end -0.7874 0.4064)
			(stroke
				(width 0.1524)
				(type default)
			)
			(layer "B.SilkS")
		)
		(fp_line
			(start 0.7874 0.4064)
			(end 0.7874 -0.4064)
			(stroke
				(width 0.1524)
				(type default)
			)
			(layer "B.SilkS")
		)
		(fp_line
			(start -0.7874 0.4064)
			(end 0.7874 0.4064)
			(stroke
				(width 0.1524)
				(type default)
			)
			(layer "B.SilkS")
		)
		(fp_line
			(start 0.67945 -0.305054)
			(end 0.12065 -0.305054)
			(stroke
				(width 0.1)
				(type default)
			)
			(layer "B.Fab")
		)
		(fp_line
			(start 0.12065 -0.305054)
			(end 0.12065 -0.2794)
			(stroke
				(width 0.1)
				(type default)
			)
			(layer "B.Fab")
		)
		(fp_line
			(start -0.12065 -0.3048)
			(end -0.67945 -0.3048)
			(stroke
				(width 0.1)
				(type default)
			)
			(layer "B.Fab")
		)
		(fp_line
			(start -0.67945 -0.3048)
			(end -0.67945 0.3048)
			(stroke
				(width 0.1)
				(type default)
			)
			(layer "B.Fab")
		)
		(fp_line
			(start 0.12065 -0.2794)
			(end -0.12065 -0.2794)
			(stroke
				(width 0.1)
				(type default)
			)
			(layer "B.Fab")
		)
		(fp_line
			(start -0.12065 -0.2794)
			(end -0.12065 -0.3048)
			(stroke
				(width 0.1)
				(type default)
			)
			(layer "B.Fab")
		)
		(fp_line
			(start 0.12065 0.2794)
			(end 0.12065 0.3048)
			(stroke
				(width 0.1)
				(type default)
			)
			(layer "B.Fab")
		)
		(fp_line
			(start -0.120396 0.2794)
			(end 0.12065 0.2794)
			(stroke
				(width 0.1)
				(type default)
			)
			(layer "B.Fab")
		)
		(fp_line
			(start 0.67945 0.3048)
			(end 0.67945 -0.305054)
			(stroke
				(width 0.1)
				(type default)
			)
			(layer "B.Fab")
		)
		(fp_line
			(start 0.12065 0.3048)
			(end 0.67945 0.3048)
			(stroke
				(width 0.1)
				(type default)
			)
			(layer "B.Fab")
		)
		(fp_line
			(start -0.120396 0.3048)
			(end -0.120396 0.2794)
			(stroke
				(width 0.1)
				(type default)
			)
			(layer "B.Fab")
		)
		(fp_line
			(start -0.67945 0.3048)
			(end -0.120396 0.3048)
			(stroke
				(width 0.1)
				(type default)
			)
			(layer "B.Fab")
		)
		(pad "1" smd circle
			(at 0.40005 0 270)
			(size 0 0)
			(layers "B.Cu" "B.Mask" "B.Paste")
			(net "P0V9_CPU0_RT2_2A")
		)
		(pad "2" smd circle
			(at -0.40005 0 270)
			(size 0 0)
			(layers "B.Cu" "B.Mask" "B.Paste")
			(net "GND")
		)
	)
	(footprint ""
		(layer "B.Cu")
		(at 322.4149 -326.227186 -90)
		(property "Reference" "PC108_2"
			(at 0 0 90)
			(layer "B.SilkS")
			(hide yes)
			(effects
				(font
					(size 1.27 1.27)
				)
				(justify mirror)
			)
		)
		(property "Value" ""
			(at 0 0 90)
			(layer "B.Fab")
			(effects
				(font
					(size 1.27 1.27)
				)
				(justify mirror)
			)
		)
		(duplicate_pad_numbers_are_jumpers no)
		(fp_line
			(start -1.524 0.762)
			(end 1.524 0.762)
			(stroke
				(width 0.1524)
				(type default)
			)
			(layer "B.SilkS")
		)
		(fp_line
			(start 1.524 0.762)
			(end 1.524 -0.762)
			(stroke
				(width 0.1524)
				(type default)
			)
			(layer "B.SilkS")
		)
		(fp_line
			(start -1.524 -0.762)
			(end -1.524 0.762)
			(stroke
				(width 0.1524)
				(type default)
			)
			(layer "B.SilkS")
		)
		(fp_line
			(start 1.524 -0.762)
			(end -1.524 -0.762)
			(stroke
				(width 0.1524)
				(type default)
			)
			(layer "B.SilkS")
		)
		(fp_line
			(start -1.1049 0.724916)
			(end -1.1049 -0.724916)
			(stroke
				(width 0.1)
				(type default)
			)
			(layer "B.Fab")
		)
		(fp_line
			(start 1.1049 0.724916)
			(end -1.1049 0.724916)
			(stroke
				(width 0.1)
				(type default)
			)
			(layer "B.Fab")
		)
		(fp_line
			(start -1.1049 -0.724916)
			(end 1.1049 -0.724916)
			(stroke
				(width 0.1)
				(type default)
			)
			(layer "B.Fab")
		)
		(fp_line
			(start 1.1049 -0.724916)
			(end 1.1049 0.724916)
			(stroke
				(width 0.1)
				(type default)
			)
			(layer "B.Fab")
		)
		(pad "1" smd rect
			(at 0.889 0 270)
			(size 1.016 1.27)
			(layers "B.Cu" "B.Mask" "B.Paste")
			(net "PVDDCR_CPU1_P0")
		)
		(pad "2" smd rect
			(at -0.889 0 270)
			(size 1.016 1.27)
			(layers "B.Cu" "B.Mask" "B.Paste")
			(net "GND")
		)
	)
	(footprint ""
		(layer "B.Cu")
		(at 364.820454 -269.30731)
		(property "Reference" "C2254"
			(at 0 0 0)
			(layer "B.SilkS")
			(hide yes)
			(effects
				(font
					(size 1.27 1.27)
				)
				(justify mirror)
			)
		)
		(property "Value" ""
			(at 0 0 0)
			(layer "B.Fab")
			(effects
				(font
					(size 1.27 1.27)
				)
				(justify mirror)
			)
		)
		(duplicate_pad_numbers_are_jumpers no)
		(fp_line
			(start -0.7874 -0.4064)
			(end -0.7874 0.4064)
			(stroke
				(width 0.1524)
				(type default)
			)
			(layer "B.SilkS")
		)
		(fp_line
			(start -0.7874 0.4064)
			(end 0.7874 0.4064)
			(stroke
				(width 0.1524)
				(type default)
			)
			(layer "B.SilkS")
		)
		(fp_line
			(start 0.7874 -0.4064)
			(end -0.7874 -0.4064)
			(stroke
				(width 0.1524)
				(type default)
			)
			(layer "B.SilkS")
		)
		(fp_line
			(start 0.7874 0.4064)
			(end 0.7874 -0.4064)
			(stroke
				(width 0.1524)
				(type default)
			)
			(layer "B.SilkS")
		)
		(fp_line
			(start -0.67945 -0.3048)
			(end -0.67945 0.3048)
			(stroke
				(width 0.1)
				(type default)
			)
			(layer "B.Fab")
		)
		(fp_line
			(start -0.67945 0.3048)
			(end -0.120396 0.3048)
			(stroke
				(width 0.1)
				(type default)
			)
			(layer "B.Fab")
		)
		(fp_line
			(start -0.12065 -0.3048)
			(end -0.67945 -0.3048)
			(stroke
				(width 0.1)
				(type default)
			)
			(layer "B.Fab")
		)
		(fp_line
			(start -0.12065 -0.2794)
			(end -0.12065 -0.3048)
			(stroke
				(width 0.1)
				(type default)
			)
			(layer "B.Fab")
		)
		(fp_line
			(start -0.120396 0.2794)
			(end 0.12065 0.2794)
			(stroke
				(width 0.1)
				(type default)
			)
			(layer "B.Fab")
		)
		(fp_line
			(start -0.120396 0.3048)
			(end -0.120396 0.2794)
			(stroke
				(width 0.1)
				(type default)
			)
			(layer "B.Fab")
		)
		(fp_line
			(start 0.12065 -0.305054)
			(end 0.12065 -0.2794)
			(stroke
				(width 0.1)
				(type default)
			)
			(layer "B.Fab")
		)
		(fp_line
			(start 0.12065 -0.2794)
			(end -0.12065 -0.2794)
			(stroke
				(width 0.1)
				(type default)
			)
			(layer "B.Fab")
		)
		(fp_line
			(start 0.12065 0.2794)
			(end 0.12065 0.3048)
			(stroke
				(width 0.1)
				(type default)
			)
			(layer "B.Fab")
		)
		(fp_line
			(start 0.12065 0.3048)
			(end 0.67945 0.3048)
			(stroke
				(width 0.1)
				(type default)
			)
			(layer "B.Fab")
		)
		(fp_line
			(start 0.67945 -0.305054)
			(end 0.12065 -0.305054)
			(stroke
				(width 0.1)
				(type default)
			)
			(layer "B.Fab")
		)
		(fp_line
			(start 0.67945 0.3048)
			(end 0.67945 -0.305054)
			(stroke
				(width 0.1)
				(type default)
			)
			(layer "B.Fab")
		)
		(pad "1" smd circle
			(at 0.40005 0 180)
			(size 0 0)
			(layers "B.Cu" "B.Mask" "B.Paste")
			(net "PVDDCR_CPU1_P0")
		)
		(pad "2" smd circle
			(at -0.40005 0 180)
			(size 0 0)
			(layers "B.Cu" "B.Mask" "B.Paste")
			(net "GND")
		)
	)
	(footprint ""
		(layer "B.Cu")
		(at 11.961114 -98.296222 180)
		(property "Reference" "C2034"
			(at 0 0 0)
			(layer "B.SilkS")
			(hide yes)
			(effects
				(font
					(size 1.27 1.27)
				)
				(justify mirror)
			)
		)
		(property "Value" ""
			(at 0 0 0)
			(layer "B.Fab")
			(effects
				(font
					(size 1.27 1.27)
				)
				(justify mirror)
			)
		)
		(duplicate_pad_numbers_are_jumpers no)
		(fp_line
			(start 0.7874 0.4064)
			(end 0.7874 -0.4064)
			(stroke
				(width 0.1524)
				(type default)
			)
			(layer "B.SilkS")
		)
		(fp_line
			(start 0.7874 -0.4064)
			(end -0.7874 -0.4064)
			(stroke
				(width 0.1524)
				(type default)
			)
			(layer "B.SilkS")
		)
		(fp_line
			(start -0.7874 0.4064)
			(end 0.7874 0.4064)
			(stroke
				(width 0.1524)
				(type default)
			)
			(layer "B.SilkS")
		)
		(fp_line
			(start -0.7874 -0.4064)
			(end -0.7874 0.4064)
			(stroke
				(width 0.1524)
				(type default)
			)
			(layer "B.SilkS")
		)
		(fp_line
			(start 0.67945 0.3048)
			(end 0.67945 -0.305054)
			(stroke
				(width 0.1)
				(type default)
			)
			(layer "B.Fab")
		)
		(fp_line
			(start 0.67945 -0.305054)
			(end 0.12065 -0.305054)
			(stroke
				(width 0.1)
				(type default)
			)
			(layer "B.Fab")
		)
		(fp_line
			(start 0.12065 0.3048)
			(end 0.67945 0.3048)
			(stroke
				(width 0.1)
				(type default)
			)
			(layer "B.Fab")
		)
		(fp_line
			(start 0.12065 0.2794)
			(end 0.12065 0.3048)
			(stroke
				(width 0.1)
				(type default)
			)
			(layer "B.Fab")
		)
		(fp_line
			(start 0.12065 -0.2794)
			(end -0.12065 -0.2794)
			(stroke
				(width 0.1)
				(type default)
			)
			(layer "B.Fab")
		)
		(fp_line
			(start 0.12065 -0.305054)
			(end 0.12065 -0.2794)
			(stroke
				(width 0.1)
				(type default)
			)
			(layer "B.Fab")
		)
		(fp_line
			(start -0.120396 0.3048)
			(end -0.120396 0.2794)
			(stroke
				(width 0.1)
				(type default)
			)
			(layer "B.Fab")
		)
		(fp_line
			(start -0.120396 0.2794)
			(end 0.12065 0.2794)
			(stroke
				(width 0.1)
				(type default)
			)
			(layer "B.Fab")
		)
		(fp_line
			(start -0.12065 -0.2794)
			(end -0.12065 -0.3048)
			(stroke
				(width 0.1)
				(type default)
			)
			(layer "B.Fab")
		)
		(fp_line
			(start -0.12065 -0.3048)
			(end -0.67945 -0.3048)
			(stroke
				(width 0.1)
				(type default)
			)
			(layer "B.Fab")
		)
		(fp_line
			(start -0.67945 0.3048)
			(end -0.120396 0.3048)
			(stroke
				(width 0.1)
				(type default)
			)
			(layer "B.Fab")
		)
		(fp_line
			(start -0.67945 -0.3048)
			(end -0.67945 0.3048)
			(stroke
				(width 0.1)
				(type default)
			)
			(layer "B.Fab")
		)
		(pad "1" smd circle
			(at 0.40005 0)
			(size 0 0)
			(layers "B.Cu" "B.Mask" "B.Paste")
			(net "P3V3_AUX_USB_HUB")
		)
		(pad "2" smd circle
			(at -0.40005 0)
			(size 0 0)
			(layers "B.Cu" "B.Mask" "B.Paste")
			(net "GND")
		)
	)
	(footprint ""
		(layer "B.Cu")
		(at 435.145942 -8.316976 -90)
		(property "Reference" "R1895"
			(at 0 0 90)
			(layer "B.SilkS")
			(hide yes)
			(effects
				(font
					(size 1.27 1.27)
				)
				(justify mirror)
			)
		)
		(property "Value" ""
			(at 0 0 90)
			(layer "B.Fab")
			(effects
				(font
					(size 1.27 1.27)
				)
				(justify mirror)
			)
		)
		(duplicate_pad_numbers_are_jumpers no)
		(fp_line
			(start -0.7874 0.4064)
			(end 0.7874 0.4064)
			(stroke
				(width 0.1524)
				(type default)
			)
			(layer "B.SilkS")
		)
		(fp_line
			(start 0.7874 0.4064)
			(end 0.7874 -0.4064)
			(stroke
				(width 0.1524)
				(type default)
			)
			(layer "B.SilkS")
		)
		(fp_line
			(start -0.7874 -0.4064)
			(end -0.7874 0.4064)
			(stroke
				(width 0.1524)
				(type default)
			)
			(layer "B.SilkS")
		)
		(fp_line
			(start 0.7874 -0.4064)
			(end -0.7874 -0.4064)
			(stroke
				(width 0.1524)
				(type default)
			)
			(layer "B.SilkS")
		)
		(fp_line
			(start -0.67945 0.3048)
			(end -0.120396 0.3048)
			(stroke
				(width 0.1)
				(type default)
			)
			(layer "B.Fab")
		)
		(fp_line
			(start -0.120396 0.3048)
			(end -0.120396 0.2794)
			(stroke
				(width 0.1)
				(type default)
			)
			(layer "B.Fab")
		)
		(fp_line
			(start 0.12065 0.3048)
			(end 0.67945 0.3048)
			(stroke
				(width 0.1)
				(type default)
			)
			(layer "B.Fab")
		)
		(fp_line
			(start 0.67945 0.3048)
			(end 0.67945 -0.305054)
			(stroke
				(width 0.1)
				(type default)
			)
			(layer "B.Fab")
		)
		(fp_line
			(start -0.120396 0.2794)
			(end 0.12065 0.2794)
			(stroke
				(width 0.1)
				(type default)
			)
			(layer "B.Fab")
		)
		(fp_line
			(start 0.12065 0.2794)
			(end 0.12065 0.3048)
			(stroke
				(width 0.1)
				(type default)
			)
			(layer "B.Fab")
		)
		(fp_line
			(start -0.12065 -0.2794)
			(end -0.12065 -0.3048)
			(stroke
				(width 0.1)
				(type default)
			)
			(layer "B.Fab")
		)
		(fp_line
			(start 0.12065 -0.2794)
			(end -0.12065 -0.2794)
			(stroke
				(width 0.1)
				(type default)
			)
			(layer "B.Fab")
		)
		(fp_line
			(start -0.67945 -0.3048)
			(end -0.67945 0.3048)
			(stroke
				(width 0.1)
				(type default)
			)
			(layer "B.Fab")
		)
		(fp_line
			(start -0.12065 -0.3048)
			(end -0.67945 -0.3048)
			(stroke
				(width 0.1)
				(type default)
			)
			(layer "B.Fab")
		)
		(fp_line
			(start 0.12065 -0.305054)
			(end 0.12065 -0.2794)
			(stroke
				(width 0.1)
				(type default)
			)
			(layer "B.Fab")
		)
		(fp_line
			(start 0.67945 -0.305054)
			(end 0.12065 -0.305054)
			(stroke
				(width 0.1)
				(type default)
			)
			(layer "B.Fab")
		)
		(pad "1" smd circle
			(at 0.40005 0 90)
			(size 0 0)
			(layers "B.Cu" "B.Mask" "B.Paste")
			(net "OCP_SFF_PRSNTA_R_N")
		)
		(pad "2" smd circle
			(at -0.40005 0 90)
			(size 0 0)
			(layers "B.Cu" "B.Mask" "B.Paste")
			(net "GND")
		)
	)
	(footprint ""
		(layer "B.Cu")
		(at 123.611386 -252.543564)
		(property "Reference" "C2429"
			(at 0 0 0)
			(layer "B.SilkS")
			(hide yes)
			(effects
				(font
					(size 1.27 1.27)
				)
				(justify mirror)
			)
		)
		(property "Value" ""
			(at 0 0 0)
			(layer "B.Fab")
			(effects
				(font
					(size 1.27 1.27)
				)
				(justify mirror)
			)
		)
		(duplicate_pad_numbers_are_jumpers no)
		(fp_line
			(start -0.7874 -0.4064)
			(end -0.7874 0.4064)
			(stroke
				(width 0.1524)
				(type default)
			)
			(layer "B.SilkS")
		)
		(fp_line
			(start -0.7874 0.4064)
			(end 0.7874 0.4064)
			(stroke
				(width 0.1524)
				(type default)
			)
			(layer "B.SilkS")
		)
		(fp_line
			(start 0.7874 -0.4064)
			(end -0.7874 -0.4064)
			(stroke
				(width 0.1524)
				(type default)
			)
			(layer "B.SilkS")
		)
		(fp_line
			(start 0.7874 0.4064)
			(end 0.7874 -0.4064)
			(stroke
				(width 0.1524)
				(type default)
			)
			(layer "B.SilkS")
		)
		(fp_line
			(start -0.67945 -0.3048)
			(end -0.67945 0.3048)
			(stroke
				(width 0.1)
				(type default)
			)
			(layer "B.Fab")
		)
		(fp_line
			(start -0.67945 0.3048)
			(end -0.120396 0.3048)
			(stroke
				(width 0.1)
				(type default)
			)
			(layer "B.Fab")
		)
		(fp_line
			(start -0.12065 -0.3048)
			(end -0.67945 -0.3048)
			(stroke
				(width 0.1)
				(type default)
			)
			(layer "B.Fab")
		)
		(fp_line
			(start -0.12065 -0.2794)
			(end -0.12065 -0.3048)
			(stroke
				(width 0.1)
				(type default)
			)
			(layer "B.Fab")
		)
		(fp_line
			(start -0.120396 0.2794)
			(end 0.12065 0.2794)
			(stroke
				(width 0.1)
				(type default)
			)
			(layer "B.Fab")
		)
		(fp_line
			(start -0.120396 0.3048)
			(end -0.120396 0.2794)
			(stroke
				(width 0.1)
				(type default)
			)
			(layer "B.Fab")
		)
		(fp_line
			(start 0.12065 -0.305054)
			(end 0.12065 -0.2794)
			(stroke
				(width 0.1)
				(type default)
			)
			(layer "B.Fab")
		)
		(fp_line
			(start 0.12065 -0.2794)
			(end -0.12065 -0.2794)
			(stroke
				(width 0.1)
				(type default)
			)
			(layer "B.Fab")
		)
		(fp_line
			(start 0.12065 0.2794)
			(end 0.12065 0.3048)
			(stroke
				(width 0.1)
				(type default)
			)
			(layer "B.Fab")
		)
		(fp_line
			(start 0.12065 0.3048)
			(end 0.67945 0.3048)
			(stroke
				(width 0.1)
				(type default)
			)
			(layer "B.Fab")
		)
		(fp_line
			(start 0.67945 -0.305054)
			(end 0.12065 -0.305054)
			(stroke
				(width 0.1)
				(type default)
			)
			(layer "B.Fab")
		)
		(fp_line
			(start 0.67945 0.3048)
			(end 0.67945 -0.305054)
			(stroke
				(width 0.1)
				(type default)
			)
			(layer "B.Fab")
		)
		(pad "1" smd circle
			(at 0.40005 0 180)
			(size 0 0)
			(layers "B.Cu" "B.Mask" "B.Paste")
			(net "PVDDCR_SOC_P1")
		)
		(pad "2" smd circle
			(at -0.40005 0 180)
			(size 0 0)
			(layers "B.Cu" "B.Mask" "B.Paste")
			(net "GND")
		)
	)
)
